FILE_TYPE=LIBRARY_PARTS;
primitive 'PCA9306DP1';
  pin
    'VREF1':
      PIN_NUMBER='(2)';
      PINUSE='POWER';
      NO_LOAD_CHECK='Both';
      NO_IO_CHECK='Both';
      NO_ASSERT_CHECK='TRUE';
      NO_DIR_CHECK='TRUE';
      ALLOW_CONNECT='TRUE';
    'SCL1':
      PIN_NUMBER='(3)';
      BIDIRECTIONAL='TRUE';
      INPUT_LOAD='(-0.01,0.01)';
      OUTPUT_LOAD='(1.0,-1.0)';
    'SDA1':
      PIN_NUMBER='(4)';
      BIDIRECTIONAL='TRUE';
      INPUT_LOAD='(-0.01,0.01)';
      OUTPUT_LOAD='(1.0,-1.0)';
    'SDA2':
      PIN_NUMBER='(5)';
      BIDIRECTIONAL='TRUE';
      INPUT_LOAD='(-0.01,0.01)';
      OUTPUT_LOAD='(1.0,-1.0)';
    'SCL2':
      PIN_NUMBER='(6)';
      BIDIRECTIONAL='TRUE';
      INPUT_LOAD='(-0.01,0.01)';
      OUTPUT_LOAD='(1.0,-1.0)';
    'VREF2':
      PIN_NUMBER='(7)';
      PINUSE='POWER';
      NO_LOAD_CHECK='Both';
      NO_IO_CHECK='Both';
      NO_ASSERT_CHECK='TRUE';
      NO_DIR_CHECK='TRUE';
      ALLOW_CONNECT='TRUE';
    'EN':
      PIN_NUMBER='(8)';
      INPUT_LOAD='(-0.01,0.01)';
    'GND':
      PIN_NUMBER='(1)';
      PINUSE='POWER';
      NO_LOAD_CHECK='Both';
      NO_IO_CHECK='Both';
      NO_ASSERT_CHECK='TRUE';
      NO_DIR_CHECK='TRUE';
      ALLOW_CONNECT='TRUE';
  end_pin;
  body
    PART_NAME='PCA9306DP1';
    BODY_NAME='PCA9306DP1';
    PHYS_DES_PREFIX='U';
    CLASS='IC';
  end_body;
end_primitive;

END.
